(kicad_pcb
	(version 20260206)
	(generator "pcbnew")
	(generator_version "10.0")
	(general
		(thickness 1.6)
		(legacy_teardrops no)
	)
	(paper "A4")
	(title_block
		(title "Wiwynn_Tioga_Pass_MB.brd")
		(comment 1 "Tioga Pass / footprints 4384-4390 of 4770")
	)
	(layers
		(0 "F.Cu" signal "TOP")
		(4 "In1.Cu" signal "L2GND")
		(6 "In2.Cu" signal "L3")
		(8 "In3.Cu" signal "L4GND")
		(10 "In4.Cu" signal "L5")
		(12 "In5.Cu" signal "L6GND")
		(14 "In6.Cu" signal "L7VCC")
		(16 "In7.Cu" signal "L8VCC")
		(18 "In8.Cu" signal "L9GND")
		(20 "In9.Cu" signal "L10")
		(22 "In10.Cu" signal "L11GND")
		(24 "In11.Cu" signal "L12")
		(26 "In12.Cu" signal "L13GND")
		(2 "B.Cu" signal "BOTTOM")
		(9 "F.Adhes" user "F.Adhesive")
		(11 "B.Adhes" user "B.Adhesive")
		(13 "F.Paste" user "Package Geometry/Pastemask Top")
		(15 "B.Paste" user "Package Geometry/Pastemask Bottom")
		(5 "F.SilkS" user "Ref Des/Silkscreen Top")
		(7 "B.SilkS" user "Ref Des/Silkscreen Bottom")
		(1 "F.Mask" user "Board Geometry/Soldermask Top")
		(3 "B.Mask" user "Board Geometry/Soldermask Bottom")
		(17 "Dwgs.User" user "User.Drawings")
		(19 "Cmts.User" user "User.Comments")
		(21 "Eco1.User" user "User.Eco1")
		(23 "Eco2.User" user "User.Eco2")
		(25 "Edge.Cuts" user "Board Geometry/Outline")
		(27 "Margin" user)
		(31 "F.CrtYd" user "Package Geometry/Place Bound Top")
		(29 "B.CrtYd" user "Package Geometry/Place Bound Bottom")
		(35 "F.Fab" user "Ref Des/Assembly Top")
		(33 "B.Fab" user "Ref Des/Assembly Bottom")
	)
	(footprint ""
		(layer "B.Cu")
		(at 493.719104 -43.056048 180)
		(property "Reference" "C25W81"
			(at 0.8382 -0.67818 180)
			(unlocked yes)
			(layer "B.SilkS")
			(effects
				(font
					(size 0.4064 0.254)
					(thickness 0.1524)
				)
				(justify left mirror)
			)
		)
		(property "Value" ""
			(at 0 0 0)
			(layer "B.Fab")
			(effects
				(font
					(size 1.27 1.27)
				)
				(justify mirror)
			)
		)
		(duplicate_pad_numbers_are_jumpers no)
		(fp_poly
			(pts
				(xy -0.3048 -0.1016) (xy -0.3048 0.9906) (xy 0.3048 0.9906) (xy 0.3048 -0.1016)
			)
			(stroke
				(width 0)
				(type default)
			)
			(fill no)
			(layer "B.CrtYd")
		)
		(fp_line
			(start 0.3048 0.9906)
			(end -0.3048 0.9906)
			(stroke
				(width 0.1)
				(type default)
			)
			(layer "B.Fab")
		)
		(fp_line
			(start 0.3048 -0.1016)
			(end 0.3048 0.9906)
			(stroke
				(width 0.1)
				(type default)
			)
			(layer "B.Fab")
		)
		(fp_line
			(start -0.3048 0.9906)
			(end -0.3048 -0.1016)
			(stroke
				(width 0.1)
				(type default)
			)
			(layer "B.Fab")
		)
		(fp_line
			(start -0.3048 -0.1016)
			(end 0.3048 -0.1016)
			(stroke
				(width 0.1)
				(type default)
			)
			(layer "B.Fab")
		)
		(pad "1" smd rect
			(at 0 0)
			(size 0.508 0.508)
			(layers "B.Cu" "B.Mask" "B.Paste")
			(net "V_IO_HSYNC_J")
		)
		(pad "2" smd rect
			(at 0 0.889)
			(size 0.508 0.508)
			(layers "B.Cu" "B.Mask" "B.Paste")
			(net "GND")
		)
		(zone
			(layer "B.Cu")
			(hatch none 0.5)
			(connect_pads
				(clearance 0)
			)
			(min_thickness 0.25)
			(keepout
				(tracks not_allowed)
				(vias allowed)
				(pads allowed)
				(copperpour not_allowed)
				(footprints allowed)
			)
			(placement
				(enabled no)
				(sheetname "")
			)
			(fill
				(thermal_gap 0.5)
				(thermal_bridge_width 0.5)
				(island_removal_mode 0)
			)
			(polygon
				(pts
					(xy 493.465104 -43.691048) (xy 493.973104 -43.691048) (xy 493.973104 -43.310048) (xy 493.465104 -43.310048)
				)
			)
		)
		(zone
			(layer "B.Cu")
			(hatch none 0.5)
			(connect_pads
				(clearance 0)
			)
			(min_thickness 0.25)
			(keepout
				(tracks allowed)
				(vias not_allowed)
				(pads allowed)
				(copperpour not_allowed)
				(footprints allowed)
			)
			(placement
				(enabled no)
				(sheetname "")
			)
			(fill
				(thermal_gap 0.5)
				(thermal_bridge_width 0.5)
				(island_removal_mode 0)
			)
			(polygon
				(pts
					(xy 493.465104 -43.310048) (xy 493.973104 -43.310048) (xy 493.973104 -43.691048) (xy 493.465104 -43.691048)
				)
			)
		)
	)
	(footprint ""
		(layer "B.Cu")
		(at 499.618 -131.6228 -90)
		(property "Reference" "C1M28"
			(at 0 0 90)
			(layer "B.SilkS")
			(hide yes)
			(effects
				(font
					(size 1.27 1.27)
				)
				(justify mirror)
			)
		)
		(property "Value" ""
			(at 0 0 90)
			(layer "B.Fab")
			(effects
				(font
					(size 1.27 1.27)
				)
				(justify mirror)
			)
		)
		(duplicate_pad_numbers_are_jumpers no)
		(fp_poly
			(pts
				(xy -0.3048 -0.1016) (xy -0.3048 0.9906) (xy 0.3048 0.9906) (xy 0.3048 -0.1016)
			)
			(stroke
				(width 0)
				(type default)
			)
			(fill no)
			(layer "B.CrtYd")
		)
		(fp_line
			(start -0.3048 0.9906)
			(end -0.3048 -0.1016)
			(stroke
				(width 0.1)
				(type default)
			)
			(layer "B.Fab")
		)
		(fp_line
			(start 0.3048 0.9906)
			(end -0.3048 0.9906)
			(stroke
				(width 0.1)
				(type default)
			)
			(layer "B.Fab")
		)
		(fp_line
			(start -0.3048 -0.1016)
			(end 0.3048 -0.1016)
			(stroke
				(width 0.1)
				(type default)
			)
			(layer "B.Fab")
		)
		(fp_line
			(start 0.3048 -0.1016)
			(end 0.3048 0.9906)
			(stroke
				(width 0.1)
				(type default)
			)
			(layer "B.Fab")
		)
		(pad "1" smd rect
			(at 0 0 90)
			(size 0.508 0.508)
			(layers "B.Cu" "B.Mask" "B.Paste")
			(net "P3V3_STBY")
		)
		(pad "2" smd rect
			(at 0 0.889 90)
			(size 0.508 0.508)
			(layers "B.Cu" "B.Mask" "B.Paste")
			(net "GND")
		)
		(zone
			(layer "B.Cu")
			(hatch none 0.5)
			(connect_pads
				(clearance 0)
			)
			(min_thickness 0.25)
			(keepout
				(tracks not_allowed)
				(vias allowed)
				(pads allowed)
				(copperpour not_allowed)
				(footprints allowed)
			)
			(placement
				(enabled no)
				(sheetname "")
			)
			(fill
				(thermal_gap 0.5)
				(thermal_bridge_width 0.5)
				(island_removal_mode 0)
			)
			(polygon
				(pts
					(xy 498.983 -131.3688) (xy 498.983 -131.8768) (xy 499.364 -131.8768) (xy 499.364 -131.3688)
				)
			)
		)
		(zone
			(layer "B.Cu")
			(hatch none 0.5)
			(connect_pads
				(clearance 0)
			)
			(min_thickness 0.25)
			(keepout
				(tracks allowed)
				(vias not_allowed)
				(pads allowed)
				(copperpour not_allowed)
				(footprints allowed)
			)
			(placement
				(enabled no)
				(sheetname "")
			)
			(fill
				(thermal_gap 0.5)
				(thermal_bridge_width 0.5)
				(island_removal_mode 0)
			)
			(polygon
				(pts
					(xy 499.364 -131.3688) (xy 499.364 -131.8768) (xy 498.983 -131.8768) (xy 498.983 -131.3688)
				)
			)
		)
	)
	(footprint ""
		(layer "B.Cu")
		(at 422.91 -5.0165 180)
		(property "Reference" "C3P46"
			(at 0 0 0)
			(layer "B.SilkS")
			(hide yes)
			(effects
				(font
					(size 1.27 1.27)
				)
				(justify mirror)
			)
		)
		(property "Value" ""
			(at 0 0 0)
			(layer "B.Fab")
			(effects
				(font
					(size 1.27 1.27)
				)
				(justify mirror)
			)
		)
		(duplicate_pad_numbers_are_jumpers no)
		(fp_rect
			(start -0.3048 0.9906)
			(end 0.3048 -0.1016)
			(stroke
				(width 0)
				(type default)
			)
			(fill no)
			(layer "B.CrtYd")
		)
		(fp_line
			(start 0.3048 0.9906)
			(end -0.3048 0.9906)
			(stroke
				(width 0.1)
				(type default)
			)
			(layer "B.Fab")
		)
		(fp_line
			(start 0.3048 -0.1016)
			(end 0.3048 0.9906)
			(stroke
				(width 0.1)
				(type default)
			)
			(layer "B.Fab")
		)
		(fp_line
			(start -0.3048 0.9906)
			(end -0.3048 -0.1016)
			(stroke
				(width 0.1)
				(type default)
			)
			(layer "B.Fab")
		)
		(fp_line
			(start -0.3048 -0.1016)
			(end 0.3048 -0.1016)
			(stroke
				(width 0.1)
				(type default)
			)
			(layer "B.Fab")
		)
		(pad "1" smd rect
			(at 0 0)
			(size 0.508 0.508)
			(layers "B.Cu" "B.Mask" "B.Paste")
			(net "P3V3_STBY")
		)
		(pad "2" smd rect
			(at 0 0.889)
			(size 0.508 0.508)
			(layers "B.Cu" "B.Mask" "B.Paste")
			(net "GND")
		)
		(zone
			(layer "B.Cu")
			(hatch none 0.5)
			(connect_pads
				(clearance 0)
			)
			(min_thickness 0.25)
			(keepout
				(tracks not_allowed)
				(vias allowed)
				(pads allowed)
				(copperpour not_allowed)
				(footprints allowed)
			)
			(placement
				(enabled no)
				(sheetname "")
			)
			(fill
				(thermal_gap 0.5)
				(thermal_bridge_width 0.5)
				(island_removal_mode 0)
			)
			(polygon
				(pts
					(xy 423.164 -5.6515) (xy 422.656 -5.6515) (xy 422.656 -5.2705) (xy 423.164 -5.2705)
				)
			)
		)
		(zone
			(layer "B.Cu")
			(hatch none 0.5)
			(connect_pads
				(clearance 0)
			)
			(min_thickness 0.25)
			(keepout
				(tracks allowed)
				(vias not_allowed)
				(pads allowed)
				(copperpour not_allowed)
				(footprints allowed)
			)
			(placement
				(enabled no)
				(sheetname "")
			)
			(fill
				(thermal_gap 0.5)
				(thermal_bridge_width 0.5)
				(island_removal_mode 0)
			)
			(polygon
				(pts
					(xy 423.164 -5.6515) (xy 422.656 -5.6515) (xy 422.656 -5.2705) (xy 423.164 -5.2705)
				)
			)
		)
	)
	(footprint ""
		(layer "B.Cu")
		(at 376.936 -66.04 180)
		(property "Reference" "R2R1"
			(at 0 0 0)
			(layer "B.SilkS")
			(hide yes)
			(effects
				(font
					(size 1.27 1.27)
				)
				(justify mirror)
			)
		)
		(property "Value" ""
			(at 0 0 0)
			(layer "B.Fab")
			(effects
				(font
					(size 1.27 1.27)
				)
				(justify mirror)
			)
		)
		(duplicate_pad_numbers_are_jumpers no)
		(fp_poly
			(pts
				(xy 0.2794 -0.1016) (xy -0.2794 -0.1016) (xy -0.2794 0.9906) (xy 0.2794 0.9906)
			)
			(stroke
				(width 0)
				(type default)
			)
			(fill no)
			(layer "B.CrtYd")
		)
		(fp_line
			(start 0.2794 0.9906)
			(end -0.2794 0.9906)
			(stroke
				(width 0.1)
				(type default)
			)
			(layer "B.Fab")
		)
		(fp_line
			(start 0.2794 -0.1016)
			(end 0.2794 0.9906)
			(stroke
				(width 0.1)
				(type default)
			)
			(layer "B.Fab")
		)
		(fp_line
			(start -0.2794 0.9906)
			(end -0.2794 -0.1016)
			(stroke
				(width 0.1)
				(type default)
			)
			(layer "B.Fab")
		)
		(fp_line
			(start -0.2794 -0.1016)
			(end 0.2794 -0.1016)
			(stroke
				(width 0.1)
				(type default)
			)
			(layer "B.Fab")
		)
		(pad "1" smd rect
			(at 0 0)
			(size 0.508 0.508)
			(layers "B.Cu" "B.Mask" "B.Paste")
			(net "P3V3_STBY")
		)
		(pad "2" smd rect
			(at 0 0.889)
			(size 0.508 0.508)
			(layers "B.Cu" "B.Mask" "B.Paste")
			(net "PU_RST_PERST_BIT0")
		)
		(zone
			(layer "B.Cu")
			(hatch none 0.5)
			(connect_pads
				(clearance 0)
			)
			(min_thickness 0.25)
			(keepout
				(tracks not_allowed)
				(vias allowed)
				(pads allowed)
				(copperpour not_allowed)
				(footprints allowed)
			)
			(placement
				(enabled no)
				(sheetname "")
			)
			(fill
				(thermal_gap 0.5)
				(thermal_bridge_width 0.5)
				(island_removal_mode 0)
			)
			(polygon
				(pts
					(xy 376.682 -66.675) (xy 377.19 -66.675) (xy 377.19 -66.294) (xy 376.682 -66.294)
				)
			)
		)
		(zone
			(layer "B.Cu")
			(hatch none 0.5)
			(connect_pads
				(clearance 0)
			)
			(min_thickness 0.25)
			(keepout
				(tracks allowed)
				(vias not_allowed)
				(pads allowed)
				(copperpour not_allowed)
				(footprints allowed)
			)
			(placement
				(enabled no)
				(sheetname "")
			)
			(fill
				(thermal_gap 0.5)
				(thermal_bridge_width 0.5)
				(island_removal_mode 0)
			)
			(polygon
				(pts
					(xy 376.682 -66.294) (xy 377.19 -66.294) (xy 377.19 -66.675) (xy 376.682 -66.675)
				)
			)
		)
	)
	(footprint ""
		(layer "B.Cu")
		(at 262.271256 -83.74634 90)
		(property "Reference" "C5P7"
			(at 0 0 90)
			(layer "B.SilkS")
			(hide yes)
			(effects
				(font
					(size 1.27 1.27)
				)
				(justify mirror)
			)
		)
		(property "Value" ""
			(at 0 0 90)
			(layer "B.Fab")
			(effects
				(font
					(size 1.27 1.27)
				)
				(justify mirror)
			)
		)
		(duplicate_pad_numbers_are_jumpers no)
		(fp_poly
			(pts
				(xy 0.7239 -0.2159) (xy -0.7239 -0.2159) (xy -0.7239 1.9939) (xy 0.7239 1.9939)
			)
			(stroke
				(width 0)
				(type default)
			)
			(fill no)
			(layer "B.CrtYd")
		)
		(fp_line
			(start 0.7239 -0.2159)
			(end 0.7239 1.9939)
			(stroke
				(width 0.1)
				(type default)
			)
			(layer "B.Fab")
		)
		(fp_line
			(start -0.7239 -0.2159)
			(end 0.7239 -0.2159)
			(stroke
				(width 0.1)
				(type default)
			)
			(layer "B.Fab")
		)
		(fp_line
			(start 0.7239 1.9939)
			(end -0.7239 1.9939)
			(stroke
				(width 0.1)
				(type default)
			)
			(layer "B.Fab")
		)
		(fp_line
			(start -0.7239 1.9939)
			(end -0.7239 -0.2159)
			(stroke
				(width 0.1)
				(type default)
			)
			(layer "B.Fab")
		)
		(pad "1" smd rect
			(at 0 0 270)
			(size 1.27 1.016)
			(layers "B.Cu" "B.Mask" "B.Paste")
			(net "PVSA_CPU0")
		)
		(pad "2" smd rect
			(at 0 1.778 270)
			(size 1.27 1.016)
			(layers "B.Cu" "B.Mask" "B.Paste")
			(net "GND")
		)
		(zone
			(layer "B.Cu")
			(hatch none 0.5)
			(connect_pads
				(clearance 0)
			)
			(min_thickness 0.25)
			(keepout
				(tracks not_allowed)
				(vias allowed)
				(pads allowed)
				(copperpour not_allowed)
				(footprints allowed)
			)
			(placement
				(enabled no)
				(sheetname "")
			)
			(fill
				(thermal_gap 0.5)
				(thermal_bridge_width 0.5)
				(island_removal_mode 0)
			)
			(polygon
				(pts
					(xy 262.779256 -84.38134) (xy 262.779256 -83.11134) (xy 263.541256 -83.11134) (xy 263.541256 -84.38134)
				)
			)
		)
	)
	(footprint ""
		(layer "B.Cu")
		(at 433.243482 -148.520658 90)
		(property "Reference" "R2L18"
			(at 0 0 90)
			(layer "B.SilkS")
			(hide yes)
			(effects
				(font
					(size 1.27 1.27)
				)
				(justify mirror)
			)
		)
		(property "Value" ""
			(at 0 0 90)
			(layer "B.Fab")
			(effects
				(font
					(size 1.27 1.27)
				)
				(justify mirror)
			)
		)
		(duplicate_pad_numbers_are_jumpers no)
		(fp_poly
			(pts
				(xy 0.2794 -0.1016) (xy -0.2794 -0.1016) (xy -0.2794 0.9906) (xy 0.2794 0.9906)
			)
			(stroke
				(width 0)
				(type default)
			)
			(fill no)
			(layer "B.CrtYd")
		)
		(fp_line
			(start 0.2794 -0.1016)
			(end 0.2794 0.9906)
			(stroke
				(width 0.1)
				(type default)
			)
			(layer "B.Fab")
		)
		(fp_line
			(start -0.2794 -0.1016)
			(end 0.2794 -0.1016)
			(stroke
				(width 0.1)
				(type default)
			)
			(layer "B.Fab")
		)
		(fp_line
			(start 0.2794 0.9906)
			(end -0.2794 0.9906)
			(stroke
				(width 0.1)
				(type default)
			)
			(layer "B.Fab")
		)
		(fp_line
			(start -0.2794 0.9906)
			(end -0.2794 -0.1016)
			(stroke
				(width 0.1)
				(type default)
			)
			(layer "B.Fab")
		)
		(pad "1" smd rect
			(at 0 0 270)
			(size 0.508 0.508)
			(layers "B.Cu" "B.Mask" "B.Paste")
			(net "PD_SATA0_CONTROLLER_TYPE_R")
		)
		(pad "2" smd rect
			(at 0 0.889 270)
			(size 0.508 0.508)
			(layers "B.Cu" "B.Mask" "B.Paste")
			(net "GND")
		)
		(zone
			(layer "B.Cu")
			(hatch none 0.5)
			(connect_pads
				(clearance 0)
			)
			(min_thickness 0.25)
			(keepout
				(tracks allowed)
				(vias not_allowed)
				(pads allowed)
				(copperpour not_allowed)
				(footprints allowed)
			)
			(placement
				(enabled no)
				(sheetname "")
			)
			(fill
				(thermal_gap 0.5)
				(thermal_bridge_width 0.5)
				(island_removal_mode 0)
			)
			(polygon
				(pts
					(xy 433.497482 -148.774658) (xy 433.497482 -148.266658) (xy 433.878482 -148.266658) (xy 433.878482 -148.774658)
				)
			)
		)
		(zone
			(layer "B.Cu")
			(hatch none 0.5)
			(connect_pads
				(clearance 0)
			)
			(min_thickness 0.25)
			(keepout
				(tracks not_allowed)
				(vias allowed)
				(pads allowed)
				(copperpour not_allowed)
				(footprints allowed)
			)
			(placement
				(enabled no)
				(sheetname "")
			)
			(fill
				(thermal_gap 0.5)
				(thermal_bridge_width 0.5)
				(island_removal_mode 0)
			)
			(polygon
				(pts
					(xy 433.878482 -148.774658) (xy 433.878482 -148.266658) (xy 433.497482 -148.266658) (xy 433.497482 -148.774658)
				)
			)
		)
	)
	(footprint ""
		(layer "B.Cu")
		(at 258.548886 -73.51014)
		(property "Reference" "C5P37"
			(at 0 0 0)
			(layer "B.SilkS")
			(hide yes)
			(effects
				(font
					(size 1.27 1.27)
				)
				(justify mirror)
			)
		)
		(property "Value" ""
			(at 0 0 0)
			(layer "B.Fab")
			(effects
				(font
					(size 1.27 1.27)
				)
				(justify mirror)
			)
		)
		(duplicate_pad_numbers_are_jumpers no)
		(fp_poly
			(pts
				(xy 0.7239 -0.2159) (xy -0.7239 -0.2159) (xy -0.7239 1.9939) (xy 0.7239 1.9939)
			)
			(stroke
				(width 0)
				(type default)
			)
			(fill no)
			(layer "B.CrtYd")
		)
		(fp_line
			(start -0.7239 -0.2159)
			(end 0.7239 -0.2159)
			(stroke
				(width 0.1)
				(type default)
			)
			(layer "B.Fab")
		)
		(fp_line
			(start -0.7239 1.9939)
			(end -0.7239 -0.2159)
			(stroke
				(width 0.1)
				(type default)
			)
			(layer "B.Fab")
		)
		(fp_line
			(start 0.7239 -0.2159)
			(end 0.7239 1.9939)
			(stroke
				(width 0.1)
				(type default)
			)
			(layer "B.Fab")
		)
		(fp_line
			(start 0.7239 1.9939)
			(end -0.7239 1.9939)
			(stroke
				(width 0.1)
				(type default)
			)
			(layer "B.Fab")
		)
		(pad "1" smd rect
			(at 0 0 180)
			(size 1.27 1.016)
			(layers "B.Cu" "B.Mask" "B.Paste")
			(net "PVCCIN_CPU0")
		)
		(pad "2" smd rect
			(at 0 1.778 180)
			(size 1.27 1.016)
			(layers "B.Cu" "B.Mask" "B.Paste")
			(net "GND")
		)
		(zone
			(layer "B.Cu")
			(hatch none 0.5)
			(connect_pads
				(clearance 0)
			)
			(min_thickness 0.25)
			(keepout
				(tracks not_allowed)
				(vias allowed)
				(pads allowed)
				(copperpour not_allowed)
				(footprints allowed)
			)
			(placement
				(enabled no)
				(sheetname "")
			)
			(fill
				(thermal_gap 0.5)
				(thermal_bridge_width 0.5)
				(island_removal_mode 0)
			)
			(polygon
				(pts
					(xy 259.183886 -73.00214) (xy 257.913886 -73.00214) (xy 257.913886 -72.24014) (xy 259.183886 -72.24014)
				)
			)
		)
	)
)
